# T6G (Grand Teton) — schematic netlist excerpt (pin names and nets, part order shuffled) for the footprints in the layout excerpt that follows; sources: Cadence DE-HDL packaged netlist, KiCad conversion of 04192023_DAF0TMB3IC0_F0TG_MB_C_brd_V02_OCP.brd

R509  Q_RES  15 1% CHIP  pkg 0402LF  page 46 : A = M_J_CPU1_ALERT_N ; B = M_J_CPU1_ALERT_R_N
C8001  Q_CAP  0.1UF 25V 10% EMPTY  pkg 0402  page 143 : A = OCP_SFF_PRSNT01_R1_N ; B = GND

(kicad_pcb
	(version 20260206)
	(generator "pcbnew")
	(generator_version "10.0")
	(general
		(thickness 1.6)
		(legacy_teardrops no)
	)
	(paper "A4")
	(title_block
		(title "04192023_DAF0TMB3IC0_F0TG_MB_C_brd_V02_OCP.brd")
		(comment 1 "Grand Teton / footprints 8229-8230 of 8354")
	)
	(layers
		(0 "F.Cu" signal "TOP")
		(4 "In1.Cu" signal "GND")
		(6 "In2.Cu" signal "IN1")
		(8 "In3.Cu" signal "GND1")
		(10 "In4.Cu" signal "IN2")
		(12 "In5.Cu" signal "GND2")
		(14 "In6.Cu" signal "IN3")
		(16 "In7.Cu" signal "GND3")
		(18 "In8.Cu" signal "VCC")
		(20 "In9.Cu" signal "VCC1")
		(22 "In10.Cu" signal "GND4")
		(24 "In11.Cu" signal "IN4")
		(26 "In12.Cu" signal "GND5")
		(28 "In13.Cu" signal "IN5")
		(30 "In14.Cu" signal "GND6")
		(32 "In15.Cu" signal "IN6")
		(34 "In16.Cu" signal "GND7")
		(2 "B.Cu" signal "BOTTOM")
		(9 "F.Adhes" user "F.Adhesive")
		(11 "B.Adhes" user "B.Adhesive")
		(13 "F.Paste" user "Package Geometry/Pastemask Top")
		(15 "B.Paste" user "Package Geometry/Pastemask Bottom")
		(5 "F.SilkS" user "Ref Des/Silkscreen Top")
		(7 "B.SilkS" user "Ref Des/Silkscreen Bottom")
		(1 "F.Mask" user "Board Geometry/Soldermask Top")
		(3 "B.Mask" user "Board Geometry/Soldermask Bottom")
		(17 "Dwgs.User" user "User.Drawings")
		(19 "Cmts.User" user "User.Comments")
		(21 "Eco1.User" user "User.Eco1")
		(23 "Eco2.User" user "User.Eco2")
		(25 "Edge.Cuts" user "Board Geometry/Outline")
		(27 "Margin" user)
		(31 "F.CrtYd" user "Package Geometry/Place Bound Top")
		(29 "B.CrtYd" user "Package Geometry/Place Bound Bottom")
		(35 "F.Fab" user "Ref Des/Assembly Top")
		(33 "B.Fab" user "Ref Des/Assembly Bottom")
	)
	(footprint ""
		(layer "B.Cu")
		(at 10.16 -81.153 -90)
		(property "Reference" "C8001"
			(at 0 0 90)
			(layer "B.SilkS")
			(hide yes)
			(effects
				(font
					(size 1.27 1.27)
				)
				(justify mirror)
			)
		)
		(property "Value" ""
			(at 0 0 90)
			(layer "B.Fab")
			(effects
				(font
					(size 1.27 1.27)
				)
				(justify mirror)
			)
		)
		(duplicate_pad_numbers_are_jumpers no)
		(fp_line
			(start -0.7874 0.4064)
			(end 0.7874 0.4064)
			(stroke
				(width 0.1524)
				(type default)
			)
			(layer "B.SilkS")
		)
		(fp_line
			(start 0.7874 0.4064)
			(end 0.7874 -0.4064)
			(stroke
				(width 0.1524)
				(type default)
			)
			(layer "B.SilkS")
		)
		(fp_line
			(start -0.7874 -0.4064)
			(end -0.7874 0.4064)
			(stroke
				(width 0.1524)
				(type default)
			)
			(layer "B.SilkS")
		)
		(fp_line
			(start 0.7874 -0.4064)
			(end -0.7874 -0.4064)
			(stroke
				(width 0.1524)
				(type default)
			)
			(layer "B.SilkS")
		)
		(fp_line
			(start -0.67945 0.3048)
			(end -0.120396 0.3048)
			(stroke
				(width 0.1)
				(type default)
			)
			(layer "B.Fab")
		)
		(fp_line
			(start -0.120396 0.3048)
			(end -0.120396 0.2794)
			(stroke
				(width 0.1)
				(type default)
			)
			(layer "B.Fab")
		)
		(fp_line
			(start 0.12065 0.3048)
			(end 0.67945 0.3048)
			(stroke
				(width 0.1)
				(type default)
			)
			(layer "B.Fab")
		)
		(fp_line
			(start 0.67945 0.3048)
			(end 0.67945 -0.305054)
			(stroke
				(width 0.1)
				(type default)
			)
			(layer "B.Fab")
		)
		(fp_line
			(start -0.120396 0.2794)
			(end 0.12065 0.2794)
			(stroke
				(width 0.1)
				(type default)
			)
			(layer "B.Fab")
		)
		(fp_line
			(start 0.12065 0.2794)
			(end 0.12065 0.3048)
			(stroke
				(width 0.1)
				(type default)
			)
			(layer "B.Fab")
		)
		(fp_line
			(start -0.12065 -0.2794)
			(end -0.12065 -0.3048)
			(stroke
				(width 0.1)
				(type default)
			)
			(layer "B.Fab")
		)
		(fp_line
			(start 0.12065 -0.2794)
			(end -0.12065 -0.2794)
			(stroke
				(width 0.1)
				(type default)
			)
			(layer "B.Fab")
		)
		(fp_line
			(start -0.67945 -0.3048)
			(end -0.67945 0.3048)
			(stroke
				(width 0.1)
				(type default)
			)
			(layer "B.Fab")
		)
		(fp_line
			(start -0.12065 -0.3048)
			(end -0.67945 -0.3048)
			(stroke
				(width 0.1)
				(type default)
			)
			(layer "B.Fab")
		)
		(fp_line
			(start 0.12065 -0.305054)
			(end 0.12065 -0.2794)
			(stroke
				(width 0.1)
				(type default)
			)
			(layer "B.Fab")
		)
		(fp_line
			(start 0.67945 -0.305054)
			(end 0.12065 -0.305054)
			(stroke
				(width 0.1)
				(type default)
			)
			(layer "B.Fab")
		)
		(pad "1" smd circle
			(at 0.40005 0 90)
			(size 0 0)
			(layers "B.Cu" "B.Mask" "B.Paste")
			(net "OCP_SFF_PRSNT01_R1_N")
		)
		(pad "2" smd circle
			(at -0.40005 0 90)
			(size 0 0)
			(layers "B.Cu" "B.Mask" "B.Paste")
			(net "GND")
		)
	)
	(footprint ""
		(layer "B.Cu")
		(at 190.163196 -244.085364)
		(property "Reference" "R509"
			(at 0 0 0)
			(layer "B.SilkS")
			(hide yes)
			(effects
				(font
					(size 1.27 1.27)
				)
				(justify mirror)
			)
		)
		(property "Value" ""
			(at 0 0 0)
			(layer "B.Fab")
			(effects
				(font
					(size 1.27 1.27)
				)
				(justify mirror)
			)
		)
		(duplicate_pad_numbers_are_jumpers no)
		(fp_line
			(start -0.7874 -0.4064)
			(end -0.7874 0.4064)
			(stroke
				(width 0.1524)
				(type default)
			)
			(layer "B.SilkS")
		)
		(fp_line
			(start -0.7874 0.4064)
			(end 0.7874 0.4064)
			(stroke
				(width 0.1524)
				(type default)
			)
			(layer "B.SilkS")
		)
		(fp_line
			(start 0.7874 -0.4064)
			(end -0.7874 -0.4064)
			(stroke
				(width 0.1524)
				(type default)
			)
			(layer "B.SilkS")
		)
		(fp_line
			(start 0.7874 0.4064)
			(end 0.7874 -0.4064)
			(stroke
				(width 0.1524)
				(type default)
			)
			(layer "B.SilkS")
		)
		(fp_line
			(start -0.67945 -0.3048)
			(end -0.67945 0.3048)
			(stroke
				(width 0.1)
				(type default)
			)
			(layer "B.Fab")
		)
		(fp_line
			(start -0.67945 0.3048)
			(end -0.120396 0.3048)
			(stroke
				(width 0.1)
				(type default)
			)
			(layer "B.Fab")
		)
		(fp_line
			(start -0.12065 -0.3048)
			(end -0.67945 -0.3048)
			(stroke
				(width 0.1)
				(type default)
			)
			(layer "B.Fab")
		)
		(fp_line
			(start -0.12065 -0.2794)
			(end -0.12065 -0.3048)
			(stroke
				(width 0.1)
				(type default)
			)
			(layer "B.Fab")
		)
		(fp_line
			(start -0.120396 0.2794)
			(end 0.12065 0.2794)
			(stroke
				(width 0.1)
				(type default)
			)
			(layer "B.Fab")
		)
		(fp_line
			(start -0.120396 0.3048)
			(end -0.120396 0.2794)
			(stroke
				(width 0.1)
				(type default)
			)
			(layer "B.Fab")
		)
		(fp_line
			(start 0.12065 -0.305054)
			(end 0.12065 -0.2794)
			(stroke
				(width 0.1)
				(type default)
			)
			(layer "B.Fab")
		)
		(fp_line
			(start 0.12065 -0.2794)
			(end -0.12065 -0.2794)
			(stroke
				(width 0.1)
				(type default)
			)
			(layer "B.Fab")
		)
		(fp_line
			(start 0.12065 0.2794)
			(end 0.12065 0.3048)
			(stroke
				(width 0.1)
				(type default)
			)
			(layer "B.Fab")
		)
		(fp_line
			(start 0.12065 0.3048)
			(end 0.67945 0.3048)
			(stroke
				(width 0.1)
				(type default)
			)
			(layer "B.Fab")
		)
		(fp_line
			(start 0.67945 -0.305054)
			(end 0.12065 -0.305054)
			(stroke
				(width 0.1)
				(type default)
			)
			(layer "B.Fab")
		)
		(fp_line
			(start 0.67945 0.3048)
			(end 0.67945 -0.305054)
			(stroke
				(width 0.1)
				(type default)
			)
			(layer "B.Fab")
		)
		(pad "1" smd circle
			(at 0.40005 0 180)
			(size 0 0)
			(layers "B.Cu" "B.Mask" "B.Paste")
			(net "M_J_CPU1_ALERT_N")
		)
		(pad "2" smd circle
			(at -0.40005 0 180)
			(size 0 0)
			(layers "B.Cu" "B.Mask" "B.Paste")
			(net "M_J_CPU1_ALERT_R_N")
		)
	)
)
